FILE_TYPE = MACRO_DRAWING;
SET COLOR_WIRE YELLOW;
SET COLOR_PROP ORANGE;
SET COLOR_DOT WHITE;
SET COLOR_ARC YELLOW;
SET COLOR_BODY GREEN;
SET COLOR_NOTE PURPLE;
SET PROP_DISPLAY VALUE;
SET PAGE_NUMBER P166;
FORCEADD QUANTA_TITLE_BLOCK_C..1
(2425 -3300);
FORCEPROP 1 LAST CUSTOM_TXT_CDS <NAME_2>
J 0
(-750 -3250);
FORCEPROP 1 LAST CUSTOM_TXT_CDS <NAME_1>
J 0
(-750 -3125);
FORCEPROP 1 LAST CUSTOM_TXT_CDS <Q_NUMBER>
J 0
(1022 -3197);
DISPLAY 1.212766 (1022 -3197);
FORCEPROP 1 LAST CUSTOM_TXT_CDS <Q_PROJ>
J 0
(43 -3198);
DISPLAY 1.212766 (43 -3198);
FORCEPROP 1 LAST CUSTOM_TXT_CDS <Q_REV>
J 0
(2241 -3197);
DISPLAY 1.212766 (2241 -3197);
FORCEPROP 1 LAST CUSTOM_TXT_CDS <CON_LAST_MODIFIED>
J 0
(540 -3285);
DISPLAY 0.978723 (540 -3285);
FORCEPROP 1 LAST CUSTOM_TXT_CDS <CON_PAGE_NUM> OF <CON_TOTAL_PAGES>
J 0
(1979 -3282);
DISPLAY 0.978723 (1979 -3282);
FORCEPROP 1 LAST Q_TITLE Blank
J 0
(-6850 -3225);
DISPLAY 2.446809 (-6850 -3225);
PAINT GREEN (-6850 -3225);
FORCEPROP 2 LAST CDS_LIB pure_quanta
J 0
(2425 -3300);
DISPLAY INVISIBLE (2425 -3300);
FORCEPROP 1 LAST CDS_LMAN_SYM_OUTLINE -9475,6775,100,-125
J 0
(2425 -3300);
DISPLAY 0.468085 (2425 -3300);
PAINT GREEN (2425 -3300);
DISPLAY INVISIBLE (2425 -3300);
FORCEPROP 2 LAST PAGE_BORDER TRUE
J 0
(-5465 1950);
DISPLAY 0.638298 (-5465 1950);
PAINT PINK (-5465 1950);
DISPLAY INVISIBLE (-5465 1950);
FORCEPROP 2 LAST CDS_XR_PAGE_TITLE CR-191 : @T6G_MB_LIB.T6G(SCH_1):PAGE191
J 0
(-5465 1950);
DISPLAY 0.638298 (-5465 1950);
PAINT PINK (-5465 1950);
DISPLAY INVISIBLE (-5465 1950);
FORCEPROP 2 LAST CUSTOM_TXT_CDS <XR_PAGE_TITLE>
J 0
(-5465 1950);
DISPLAY 0.638298 (-5465 1950);
PAINT PINK (-5465 1950);
DISPLAY INVISIBLE (-5465 1950);
FORCEPROP 1 LAST COMMENT_BODY TRUE
J 0
(2437 -3313);
DISPLAY 0.978723 (2437 -3313);
PAINT GREEN (2437 -3313);
DISPLAY INVISIBLE (2437 -3313);
FORCEPROP 1 LAST Q_DEPT BU9
J 1
(-1338 -3251);
DISPLAY 1.957447 (-1338 -3251);
PAINT GREEN (-1338 -3251);
DISPLAY INVISIBLE (-1338 -3251);
FORCEPROP 0 LAST CDS_CON_LAST_MODIFIED Thu Aug 24 10:15:04 2023
J 0
(540 -3285);
DISPLAY INVISIBLE (540 -3285);
QUIT
